(kicad_pcb
	(version 20260206)
	(generator "pcbnew")
	(generator_version "10.0")
	(general
		(thickness 1.6)
		(legacy_teardrops no)
	)
	(paper "A4")
	(title_block
		(title "12092022_DA0F0TMDCD0_F0T_Management_Board_D_brd_V3_OCP.brd")
		(comment 1 "Grand Teton / footprints 491-496 of 1440")
	)
	(layers
		(0 "F.Cu" signal "TOP")
		(4 "In1.Cu" signal "GND")
		(6 "In2.Cu" signal "IN1")
		(8 "In3.Cu" signal "GND1")
		(10 "In4.Cu" signal "IN2")
		(12 "In5.Cu" signal "VCC")
		(14 "In6.Cu" signal "VCC1")
		(16 "In7.Cu" signal "IN3")
		(18 "In8.Cu" signal "GND2")
		(20 "In9.Cu" signal "IN4")
		(22 "In10.Cu" signal "GND3")
		(2 "B.Cu" signal "BOTTOM")
		(9 "F.Adhes" user "F.Adhesive")
		(11 "B.Adhes" user "B.Adhesive")
		(13 "F.Paste" user "Package Geometry/Pastemask Top")
		(15 "B.Paste" user "Package Geometry/Pastemask Bottom")
		(5 "F.SilkS" user "Ref Des/Silkscreen Top")
		(7 "B.SilkS" user "Ref Des/Silkscreen Bottom")
		(1 "F.Mask" user "Board Geometry/Soldermask Top")
		(3 "B.Mask" user "Board Geometry/Soldermask Bottom")
		(17 "Dwgs.User" user "User.Drawings")
		(19 "Cmts.User" user "User.Comments")
		(21 "Eco1.User" user "User.Eco1")
		(23 "Eco2.User" user "User.Eco2")
		(25 "Edge.Cuts" user "Board Geometry/Outline")
		(27 "Margin" user)
		(31 "F.CrtYd" user "Package Geometry/Place Bound Top")
		(29 "B.CrtYd" user "Package Geometry/Place Bound Bottom")
		(35 "F.Fab" user "Ref Des/Assembly Top")
		(33 "B.Fab" user "Ref Des/Assembly Bottom")
	)
	(footprint ""
		(layer "F.Cu")
		(at 22.225 -62.3062 90)
		(property "Reference" "U50"
			(at -3.40487 1.016 0)
			(unlocked yes)
			(layer "F.SilkS")
			(effects
				(font
					(size 0.7874 0.5842)
					(thickness 0.1524)
				)
			)
		)
		(property "Value" ""
			(at 0 0 90)
			(layer "F.Fab")
			(effects
				(font
					(size 1.27 1.27)
				)
			)
		)
		(duplicate_pad_numbers_are_jumpers no)
		(fp_line
			(start 1.7272 -1.1176)
			(end 0.254 -1.1176)
			(stroke
				(width 0.1524)
				(type default)
			)
			(layer "F.SilkS")
		)
		(fp_line
			(start 1.7272 -1.1176)
			(end 1.7272 1.1176)
			(stroke
				(width 0.1524)
				(type default)
			)
			(layer "F.SilkS")
		)
		(fp_line
			(start 0.254 -1.1176)
			(end 0 -0.7366)
			(stroke
				(width 0.1524)
				(type default)
			)
			(layer "F.SilkS")
		)
		(fp_line
			(start -0.254 -1.1176)
			(end -1.7272 -1.1176)
			(stroke
				(width 0.1524)
				(type default)
			)
			(layer "F.SilkS")
		)
		(fp_line
			(start 0 -0.7366)
			(end -0.254 -1.1176)
			(stroke
				(width 0.1524)
				(type default)
			)
			(layer "F.SilkS")
		)
		(fp_line
			(start 1.7272 1.1176)
			(end -1.7272 1.1176)
			(stroke
				(width 0.1524)
				(type default)
			)
			(layer "F.SilkS")
		)
		(fp_line
			(start -1.7272 1.1176)
			(end -1.7272 -1.1176)
			(stroke
				(width 0.1524)
				(type default)
			)
			(layer "F.SilkS")
		)
		(fp_poly
			(pts
				(xy -1.9558 -0.649986) (xy -2.7178 -0.268986) (xy -2.7178 -1.030986)
			)
			(stroke
				(width 0)
				(type default)
			)
			(fill yes)
			(layer "F.SilkS")
		)
		(fp_line
			(start 1.5748 -1.1176)
			(end -1.5748 -1.1176)
			(stroke
				(width 0.1)
				(type default)
			)
			(layer "F.Fab")
		)
		(fp_line
			(start -1.5748 -1.1176)
			(end -1.5748 1.1176)
			(stroke
				(width 0.1)
				(type default)
			)
			(layer "F.Fab")
		)
		(fp_line
			(start 1.5748 1.1176)
			(end 1.5748 -1.1176)
			(stroke
				(width 0.1)
				(type default)
			)
			(layer "F.Fab")
		)
		(fp_line
			(start -1.5748 1.1176)
			(end 1.5748 1.1176)
			(stroke
				(width 0.1)
				(type default)
			)
			(layer "F.Fab")
		)
		(fp_poly
			(pts
				(xy -1.9558 -0.649986) (xy -2.7178 -0.268986) (xy -2.7178 -1.030986)
			)
			(stroke
				(width 0)
				(type default)
			)
			(fill yes)
			(layer "F.Fab")
		)
		(pad "1" smd rect
			(at -0.999998 -0.649986)
			(size 0.3556 1.1176)
			(layers "F.Cu" "F.Mask" "F.Paste")
			(net "UART_BIC_DBG_TX_R")
		)
		(pad "2" smd rect
			(at -0.999998 0)
			(size 0.3556 1.1176)
			(layers "F.Cu" "F.Mask" "F.Paste")
			(net "GND")
		)
		(pad "3" smd rect
			(at -0.999998 0.649986)
			(size 0.3556 1.1176)
			(layers "F.Cu" "F.Mask" "F.Paste")
			(net "UART_6_BMC_RXD_R")
		)
		(pad "4" smd rect
			(at 0.999998 0.649986)
			(size 0.3556 1.1176)
			(layers "F.Cu" "F.Mask" "F.Paste")
			(net "UART_BIC_GF_RXD")
		)
		(pad "5" smd rect
			(at 0.999998 0)
			(size 0.3556 1.1176)
			(layers "F.Cu" "F.Mask" "F.Paste")
			(net "P3V3_AUX")
		)
		(pad "6" smd rect
			(at 0.999998 -0.649986)
			(size 0.3556 1.1176)
			(layers "F.Cu" "F.Mask" "F.Paste")
			(net "FM_BIC_DEBUG_SW_N")
		)
	)
	(footprint ""
		(layer "F.Cu")
		(at 27.1272 -21.971 -90)
		(property "Reference" "R91"
			(at 0 0 270)
			(layer "F.SilkS")
			(hide yes)
			(effects
				(font
					(size 1.27 1.27)
				)
			)
		)
		(property "Value" ""
			(at 0 0 270)
			(layer "F.Fab")
			(effects
				(font
					(size 1.27 1.27)
				)
			)
		)
		(duplicate_pad_numbers_are_jumpers no)
		(fp_line
			(start -0.7874 0.4064)
			(end -0.7874 -0.4064)
			(stroke
				(width 0.1524)
				(type default)
			)
			(layer "F.SilkS")
		)
		(fp_line
			(start 0.7874 0.4064)
			(end -0.7874 0.4064)
			(stroke
				(width 0.1524)
				(type default)
			)
			(layer "F.SilkS")
		)
		(fp_line
			(start -0.7874 -0.4064)
			(end 0.7874 -0.4064)
			(stroke
				(width 0.1524)
				(type default)
			)
			(layer "F.SilkS")
		)
		(fp_line
			(start 0.7874 -0.4064)
			(end 0.7874 0.4064)
			(stroke
				(width 0.1524)
				(type default)
			)
			(layer "F.SilkS")
		)
		(fp_line
			(start -0.67945 0.3048)
			(end -0.67945 -0.305054)
			(stroke
				(width 0.1)
				(type default)
			)
			(layer "F.Fab")
		)
		(fp_line
			(start -0.12065 0.3048)
			(end -0.67945 0.3048)
			(stroke
				(width 0.1)
				(type default)
			)
			(layer "F.Fab")
		)
		(fp_line
			(start 0.120396 0.3048)
			(end 0.120396 0.2794)
			(stroke
				(width 0.1)
				(type default)
			)
			(layer "F.Fab")
		)
		(fp_line
			(start 0.67945 0.3048)
			(end 0.120396 0.3048)
			(stroke
				(width 0.1)
				(type default)
			)
			(layer "F.Fab")
		)
		(fp_line
			(start -0.12065 0.2794)
			(end -0.12065 0.3048)
			(stroke
				(width 0.1)
				(type default)
			)
			(layer "F.Fab")
		)
		(fp_line
			(start 0.120396 0.2794)
			(end -0.12065 0.2794)
			(stroke
				(width 0.1)
				(type default)
			)
			(layer "F.Fab")
		)
		(fp_line
			(start -0.12065 -0.2794)
			(end 0.12065 -0.2794)
			(stroke
				(width 0.1)
				(type default)
			)
			(layer "F.Fab")
		)
		(fp_line
			(start 0.12065 -0.2794)
			(end 0.12065 -0.3048)
			(stroke
				(width 0.1)
				(type default)
			)
			(layer "F.Fab")
		)
		(fp_line
			(start 0.12065 -0.3048)
			(end 0.67945 -0.3048)
			(stroke
				(width 0.1)
				(type default)
			)
			(layer "F.Fab")
		)
		(fp_line
			(start 0.67945 -0.3048)
			(end 0.67945 0.3048)
			(stroke
				(width 0.1)
				(type default)
			)
			(layer "F.Fab")
		)
		(fp_line
			(start -0.67945 -0.305054)
			(end -0.12065 -0.305054)
			(stroke
				(width 0.1)
				(type default)
			)
			(layer "F.Fab")
		)
		(fp_line
			(start -0.12065 -0.305054)
			(end -0.12065 -0.2794)
			(stroke
				(width 0.1)
				(type default)
			)
			(layer "F.Fab")
		)
		(pad "1" smd circle
			(at -0.40005 0 270)
			(size 0 0)
			(layers "F.Cu" "F.Mask" "F.Paste")
			(net "CRT_VCC5")
		)
		(pad "2" smd circle
			(at 0.40005 0 270)
			(size 0 0)
			(layers "F.Cu" "F.Mask" "F.Paste")
			(net "V_BMC_LS_DDC_SDA")
		)
	)
	(footprint ""
		(layer "F.Cu")
		(at 41.913302 -63.756794 90)
		(property "Reference" "R201"
			(at 0 0 90)
			(layer "F.SilkS")
			(hide yes)
			(effects
				(font
					(size 1.27 1.27)
				)
			)
		)
		(property "Value" ""
			(at 0 0 90)
			(layer "F.Fab")
			(effects
				(font
					(size 1.27 1.27)
				)
			)
		)
		(duplicate_pad_numbers_are_jumpers no)
		(fp_line
			(start 0.7874 -0.4064)
			(end 0.7874 0.4064)
			(stroke
				(width 0.1524)
				(type default)
			)
			(layer "F.SilkS")
		)
		(fp_line
			(start -0.7874 -0.4064)
			(end 0.7874 -0.4064)
			(stroke
				(width 0.1524)
				(type default)
			)
			(layer "F.SilkS")
		)
		(fp_line
			(start 0.7874 0.4064)
			(end -0.7874 0.4064)
			(stroke
				(width 0.1524)
				(type default)
			)
			(layer "F.SilkS")
		)
		(fp_line
			(start -0.7874 0.4064)
			(end -0.7874 -0.4064)
			(stroke
				(width 0.1524)
				(type default)
			)
			(layer "F.SilkS")
		)
		(fp_line
			(start -0.12065 -0.305054)
			(end -0.12065 -0.2794)
			(stroke
				(width 0.1)
				(type default)
			)
			(layer "F.Fab")
		)
		(fp_line
			(start -0.67945 -0.305054)
			(end -0.12065 -0.305054)
			(stroke
				(width 0.1)
				(type default)
			)
			(layer "F.Fab")
		)
		(fp_line
			(start 0.67945 -0.3048)
			(end 0.67945 0.3048)
			(stroke
				(width 0.1)
				(type default)
			)
			(layer "F.Fab")
		)
		(fp_line
			(start 0.12065 -0.3048)
			(end 0.67945 -0.3048)
			(stroke
				(width 0.1)
				(type default)
			)
			(layer "F.Fab")
		)
		(fp_line
			(start 0.12065 -0.2794)
			(end 0.12065 -0.3048)
			(stroke
				(width 0.1)
				(type default)
			)
			(layer "F.Fab")
		)
		(fp_line
			(start -0.12065 -0.2794)
			(end 0.12065 -0.2794)
			(stroke
				(width 0.1)
				(type default)
			)
			(layer "F.Fab")
		)
		(fp_line
			(start 0.120396 0.2794)
			(end -0.12065 0.2794)
			(stroke
				(width 0.1)
				(type default)
			)
			(layer "F.Fab")
		)
		(fp_line
			(start -0.12065 0.2794)
			(end -0.12065 0.3048)
			(stroke
				(width 0.1)
				(type default)
			)
			(layer "F.Fab")
		)
		(fp_line
			(start 0.67945 0.3048)
			(end 0.120396 0.3048)
			(stroke
				(width 0.1)
				(type default)
			)
			(layer "F.Fab")
		)
		(fp_line
			(start 0.120396 0.3048)
			(end 0.120396 0.2794)
			(stroke
				(width 0.1)
				(type default)
			)
			(layer "F.Fab")
		)
		(fp_line
			(start -0.12065 0.3048)
			(end -0.67945 0.3048)
			(stroke
				(width 0.1)
				(type default)
			)
			(layer "F.Fab")
		)
		(fp_line
			(start -0.67945 0.3048)
			(end -0.67945 -0.305054)
			(stroke
				(width 0.1)
				(type default)
			)
			(layer "F.Fab")
		)
		(pad "1" smd circle
			(at -0.40005 0 90)
			(size 0 0)
			(layers "F.Cu" "F.Mask" "F.Paste")
			(net "I3C4_SDA_R")
		)
		(pad "2" smd circle
			(at 0.40005 0 90)
			(size 0 0)
			(layers "F.Cu" "F.Mask" "F.Paste")
			(net "I3C4_SPD_SDA")
		)
	)
	(footprint ""
		(layer "F.Cu")
		(at 11.551666 -12.546838 90)
		(property "Reference" "U31"
			(at -0.608838 -1.618996 90)
			(unlocked yes)
			(layer "F.SilkS")
			(effects
				(font
					(size 0.7874 0.5842)
					(thickness 0.1524)
				)
				(justify left)
			)
		)
		(property "Value" ""
			(at 0 0 90)
			(layer "F.Fab")
			(effects
				(font
					(size 1.27 1.27)
				)
			)
		)
		(duplicate_pad_numbers_are_jumpers no)
		(fp_line
			(start 1.4986 -1.100074)
			(end 1.4986 1.100074)
			(stroke
				(width 0.1524)
				(type default)
			)
			(layer "F.SilkS")
		)
		(fp_line
			(start -1.4986 -1.100074)
			(end 1.4986 -1.100074)
			(stroke
				(width 0.1524)
				(type default)
			)
			(layer "F.SilkS")
		)
		(fp_line
			(start 1.4986 1.100074)
			(end -1.4986 1.100074)
			(stroke
				(width 0.1524)
				(type default)
			)
			(layer "F.SilkS")
		)
		(fp_line
			(start -1.4986 1.100074)
			(end -1.4986 -1.100074)
			(stroke
				(width 0.1524)
				(type default)
			)
			(layer "F.SilkS")
		)
		(fp_poly
			(pts
				(xy -2.321052 -1.41732) (xy -1.879346 -1.859026) (xy -1.719834 -1.235456)
			)
			(stroke
				(width 0)
				(type default)
			)
			(fill yes)
			(layer "F.SilkS")
		)
		(fp_line
			(start 0.67437 -1.100074)
			(end 0.67437 1.100074)
			(stroke
				(width 0.1)
				(type default)
			)
			(layer "F.Fab")
		)
		(fp_line
			(start -0.67437 -1.100074)
			(end 0.67437 -1.100074)
			(stroke
				(width 0.1)
				(type default)
			)
			(layer "F.Fab")
		)
		(fp_line
			(start 0.67437 1.100074)
			(end -0.67437 1.100074)
			(stroke
				(width 0.1)
				(type default)
			)
			(layer "F.Fab")
		)
		(fp_line
			(start -0.67437 1.100074)
			(end -0.67437 -1.100074)
			(stroke
				(width 0.1)
				(type default)
			)
			(layer "F.Fab")
		)
		(fp_poly
			(pts
				(xy -2.20472 -0.338328) (xy -2.20472 -0.963168) (xy -1.651 -0.635)
			)
			(stroke
				(width 0)
				(type default)
			)
			(fill yes)
			(layer "F.Fab")
		)
		(pad "1" smd rect
			(at -0.889 -0.649986 90)
			(size 1.016 0.381)
			(layers "F.Cu" "F.Mask" "F.Paste")
			(net "TP_PWR_BUF")
		)
		(pad "2" smd rect
			(at -0.889 0 90)
			(size 1.016 0.381)
			(layers "F.Cu" "F.Mask" "F.Paste")
			(net "REAR_PWR_BTN_N")
		)
		(pad "3" smd rect
			(at -0.889 0.649986 90)
			(size 1.016 0.381)
			(layers "F.Cu" "F.Mask" "F.Paste")
			(net "GND")
		)
		(pad "4" smd rect
			(at 0.889 0.649986 90)
			(size 1.016 0.381)
			(layers "F.Cu" "F.Mask" "F.Paste")
			(net "PWR_BTN_BMC_N")
		)
		(pad "5" smd rect
			(at 0.889 -0.649986 90)
			(size 1.016 0.381)
			(layers "F.Cu" "F.Mask" "F.Paste")
			(net "P3V3_AUX")
		)
	)
	(footprint ""
		(layer "F.Cu")
		(at 12.4206 -101.0539)
		(property "Reference" "R472"
			(at 0 0 0)
			(layer "F.SilkS")
			(hide yes)
			(effects
				(font
					(size 1.27 1.27)
				)
			)
		)
		(property "Value" ""
			(at 0 0 0)
			(layer "F.Fab")
			(effects
				(font
					(size 1.27 1.27)
				)
			)
		)
		(duplicate_pad_numbers_are_jumpers no)
		(fp_line
			(start -0.7874 -0.4064)
			(end 0.7874 -0.4064)
			(stroke
				(width 0.1524)
				(type default)
			)
			(layer "F.SilkS")
		)
		(fp_line
			(start -0.7874 0.4064)
			(end -0.7874 -0.4064)
			(stroke
				(width 0.1524)
				(type default)
			)
			(layer "F.SilkS")
		)
		(fp_line
			(start 0.7874 -0.4064)
			(end 0.7874 0.4064)
			(stroke
				(width 0.1524)
				(type default)
			)
			(layer "F.SilkS")
		)
		(fp_line
			(start 0.7874 0.4064)
			(end -0.7874 0.4064)
			(stroke
				(width 0.1524)
				(type default)
			)
			(layer "F.SilkS")
		)
		(fp_line
			(start -0.67945 -0.305054)
			(end -0.12065 -0.305054)
			(stroke
				(width 0.1)
				(type default)
			)
			(layer "F.Fab")
		)
		(fp_line
			(start -0.67945 0.3048)
			(end -0.67945 -0.305054)
			(stroke
				(width 0.1)
				(type default)
			)
			(layer "F.Fab")
		)
		(fp_line
			(start -0.12065 -0.305054)
			(end -0.12065 -0.2794)
			(stroke
				(width 0.1)
				(type default)
			)
			(layer "F.Fab")
		)
		(fp_line
			(start -0.12065 -0.2794)
			(end 0.12065 -0.2794)
			(stroke
				(width 0.1)
				(type default)
			)
			(layer "F.Fab")
		)
		(fp_line
			(start -0.12065 0.2794)
			(end -0.12065 0.3048)
			(stroke
				(width 0.1)
				(type default)
			)
			(layer "F.Fab")
		)
		(fp_line
			(start -0.12065 0.3048)
			(end -0.67945 0.3048)
			(stroke
				(width 0.1)
				(type default)
			)
			(layer "F.Fab")
		)
		(fp_line
			(start 0.120396 0.2794)
			(end -0.12065 0.2794)
			(stroke
				(width 0.1)
				(type default)
			)
			(layer "F.Fab")
		)
		(fp_line
			(start 0.120396 0.3048)
			(end 0.120396 0.2794)
			(stroke
				(width 0.1)
				(type default)
			)
			(layer "F.Fab")
		)
		(fp_line
			(start 0.12065 -0.3048)
			(end 0.67945 -0.3048)
			(stroke
				(width 0.1)
				(type default)
			)
			(layer "F.Fab")
		)
		(fp_line
			(start 0.12065 -0.2794)
			(end 0.12065 -0.3048)
			(stroke
				(width 0.1)
				(type default)
			)
			(layer "F.Fab")
		)
		(fp_line
			(start 0.67945 -0.3048)
			(end 0.67945 0.3048)
			(stroke
				(width 0.1)
				(type default)
			)
			(layer "F.Fab")
		)
		(fp_line
			(start 0.67945 0.3048)
			(end 0.120396 0.3048)
			(stroke
				(width 0.1)
				(type default)
			)
			(layer "F.Fab")
		)
		(pad "1" smd circle
			(at -0.40005 0)
			(size 0 0)
			(layers "F.Cu" "F.Mask" "F.Paste")
			(net "P3V3_AUX")
		)
		(pad "2" smd circle
			(at 0.40005 0)
			(size 0 0)
			(layers "F.Cu" "F.Mask" "F.Paste")
			(net "AC_PWR_BTN_R1_N")
		)
	)
	(footprint ""
		(layer "F.Cu")
		(at 84.455 -76.6572 90)
		(property "Reference" "R276"
			(at 0 0 90)
			(layer "F.SilkS")
			(hide yes)
			(effects
				(font
					(size 1.27 1.27)
				)
			)
		)
		(property "Value" ""
			(at 0 0 90)
			(layer "F.Fab")
			(effects
				(font
					(size 1.27 1.27)
				)
			)
		)
		(duplicate_pad_numbers_are_jumpers no)
		(fp_line
			(start 0.7874 -0.4064)
			(end 0.7874 0.4064)
			(stroke
				(width 0.1524)
				(type default)
			)
			(layer "F.SilkS")
		)
		(fp_line
			(start -0.7874 -0.4064)
			(end 0.7874 -0.4064)
			(stroke
				(width 0.1524)
				(type default)
			)
			(layer "F.SilkS")
		)
		(fp_line
			(start 0.7874 0.4064)
			(end -0.7874 0.4064)
			(stroke
				(width 0.1524)
				(type default)
			)
			(layer "F.SilkS")
		)
		(fp_line
			(start -0.7874 0.4064)
			(end -0.7874 -0.4064)
			(stroke
				(width 0.1524)
				(type default)
			)
			(layer "F.SilkS")
		)
		(fp_line
			(start -0.12065 -0.305054)
			(end -0.12065 -0.2794)
			(stroke
				(width 0.1)
				(type default)
			)
			(layer "F.Fab")
		)
		(fp_line
			(start -0.67945 -0.305054)
			(end -0.12065 -0.305054)
			(stroke
				(width 0.1)
				(type default)
			)
			(layer "F.Fab")
		)
		(fp_line
			(start 0.67945 -0.3048)
			(end 0.67945 0.3048)
			(stroke
				(width 0.1)
				(type default)
			)
			(layer "F.Fab")
		)
		(fp_line
			(start 0.12065 -0.3048)
			(end 0.67945 -0.3048)
			(stroke
				(width 0.1)
				(type default)
			)
			(layer "F.Fab")
		)
		(fp_line
			(start 0.12065 -0.2794)
			(end 0.12065 -0.3048)
			(stroke
				(width 0.1)
				(type default)
			)
			(layer "F.Fab")
		)
		(fp_line
			(start -0.12065 -0.2794)
			(end 0.12065 -0.2794)
			(stroke
				(width 0.1)
				(type default)
			)
			(layer "F.Fab")
		)
		(fp_line
			(start 0.120396 0.2794)
			(end -0.12065 0.2794)
			(stroke
				(width 0.1)
				(type default)
			)
			(layer "F.Fab")
		)
		(fp_line
			(start -0.12065 0.2794)
			(end -0.12065 0.3048)
			(stroke
				(width 0.1)
				(type default)
			)
			(layer "F.Fab")
		)
		(fp_line
			(start 0.67945 0.3048)
			(end 0.120396 0.3048)
			(stroke
				(width 0.1)
				(type default)
			)
			(layer "F.Fab")
		)
		(fp_line
			(start 0.120396 0.3048)
			(end 0.120396 0.2794)
			(stroke
				(width 0.1)
				(type default)
			)
			(layer "F.Fab")
		)
		(fp_line
			(start -0.12065 0.3048)
			(end -0.67945 0.3048)
			(stroke
				(width 0.1)
				(type default)
			)
			(layer "F.Fab")
		)
		(fp_line
			(start -0.67945 0.3048)
			(end -0.67945 -0.305054)
			(stroke
				(width 0.1)
				(type default)
			)
			(layer "F.Fab")
		)
		(pad "1" smd circle
			(at -0.40005 0 90)
			(size 0 0)
			(layers "F.Cu" "F.Mask" "F.Paste")
			(net "PWRGD_P1V2_AUX_R")
		)
		(pad "2" smd circle
			(at 0.40005 0 90)
			(size 0 0)
			(layers "F.Cu" "F.Mask" "F.Paste")
			(net "PWRGD_P1V2_AUX")
		)
	)
)
